FILE_TYPE = MACRO_DRAWING;
SET COLOR_WIRE YELLOW;
SET COLOR_PROP ORANGE;
SET COLOR_DOT WHITE;
SET COLOR_ARC YELLOW;
SET COLOR_BODY GREEN;
SET COLOR_NOTE PURPLE;
SET PROP_DISPLAY VALUE;
SET PAGE_NUMBER P54;
SET PATH_NUMBER P141;
FORCEADD Q_CAP..1
(-1075 1425);
FORCEPROP 1 LAST MATERIAL EMPTY
J 0
(-1025 1325);
DISPLAY 0.978723 (-1025 1325);
FORCEPROP 1 LAST TOLERANCE 10%
J 0
(-1025 1375);
DISPLAY 0.978723 (-1025 1375);
FORCEPROP 1 LAST VOLTAGE 50V
J 0
(-1025 1425);
DISPLAY 0.978723 (-1025 1425);
FORCEPROP 1 LAST VALUE 0.001UF
J 0
(-1025 1475);
DISPLAY 0.978723 (-1025 1475);
FORCEPROP 1 LAST PACK_TYPE C0402
J 0
(-1025 1225);
DISPLAY 0.978723 (-1025 1225);
FORCEPROP 1 LAST PART_NUMBER CH30106KB19
J 0
(-1025 1275);
DISPLAY 0.978723 (-1025 1275);
FORCEPROP 2 LAST CDS_LIB pure_quanta
J 0
(-1075 1425);
DISPLAY INVISIBLE (-1075 1425);
FORCEPROP 1 LAST PATH I100
J 0
(-1025 1575);
DISPLAY 0.978723 (-1025 1575);
PAINT WHITE (-1025 1575);
DISPLAY INVISIBLE (-1025 1575);
FORCEPROP 1 LAST LOCATION C154
J 0
(-1025 1525);
DISPLAY 0.978723 (-1025 1525);
FORCEPROP 1 LASTPIN (-1075 1525) $PN 1
J 0
(-1065 1505);
DISPLAY 0.787234 (-1065 1505);
PAINT MONO (-1065 1505);
FORCEPROP 1 LASTPIN (-1075 1325) $PN 2
J 0
(-1065 1305);
DISPLAY 0.787234 (-1065 1305);
PAINT MONO (-1065 1305);
FORCEPROP 0 LAST $SEC 1
J 0
(-1025 1575);
DISPLAY 0.680851 (-1025 1575);
PAINT MONO (-1025 1575);
DISPLAY INVISIBLE (-1025 1575);
FORCEPROP 0 LAST CDS_SEC 1
J 0
(-1025 1575);
DISPLAY 0.680851 (-1025 1575);
DISPLAY INVISIBLE (-1025 1575);
FORCEADD UNIVERSAL_GND..1
(-1075 1225);
FORCEPROP 3 LASTPIN (-1075 1275) SIG_NAME GND\g
J 0
(-1065 1285);
DISPLAY 0.659574 (-1065 1285);
PAINT MONO (-1065 1285);
DISPLAY INVISIBLE (-1065 1285);
FORCEPROP 1 LAST PATH I101
J 0
(-1000 1225);
DISPLAY 0.872340 (-1000 1225);
PAINT AQUA (-1000 1225);
DISPLAY INVISIBLE (-1000 1225);
FORCEPROP 1 LAST HDL_POWER GND
J 1
(-1050 1150);
DISPLAY 0.702128 (-1050 1150);
PAINT GREEN (-1050 1150);
DISPLAY INVISIBLE (-1050 1150);
FORCEPROP 2 LAST CDS_LIB logical_power
J 0
(-1075 1225);
DISPLAY INVISIBLE (-1075 1225);
FORCEADD Q_RES..1
(-1625 2175);
FORCEPROP 1 LAST VALUE 0
J 2
(-1775 2175);
DISPLAY 0.978723 (-1775 2175);
FORCEPROP 1 LAST MATERIAL CHIP
J 0
(-1875 2225);
DISPLAY 0.978723 (-1875 2225);
FORCEPROP 1 LAST PART_NUMBER CS00002JB13
J 0
(-1850 2275);
DISPLAY 0.978723 (-1850 2275);
FORCEPROP 1 LAST TOLERANCE 5%
J 0
(-2025 2100);
DISPLAY 0.978723 (-2025 2100);
FORCEPROP 1 LAST WATTAGE 1/16W
J 2
(-1700 2100);
DISPLAY 0.978723 (-1700 2100);
FORCEPROP 1 LAST PACK_TYPE 0402LF
J 0
(-1675 2100);
DISPLAY 0.978723 (-1675 2100);
FORCEPROP 2 LAST CDS_LIB pure_quanta
J 0
(-1625 2175);
DISPLAY INVISIBLE (-1625 2175);
FORCEPROP 1 LAST PATH I102
J 0
(-1675 2325);
DISPLAY 0.978723 (-1675 2325);
PAINT WHITE (-1675 2325);
DISPLAY INVISIBLE (-1675 2325);
FORCEPROP 1 LAST LOCATION R393
J 0
(-1675 2225);
DISPLAY 0.978723 (-1675 2225);
FORCEPROP 1 LASTPIN (-1725 2175) $PN 1
J 0
(-1713 2187);
DISPLAY 0.787234 (-1713 2187);
PAINT MONO (-1713 2187);
FORCEPROP 1 LASTPIN (-1525 2175) $PN 2
J 0
(-1563 2187);
DISPLAY 0.787234 (-1563 2187);
PAINT MONO (-1563 2187);
FORCEPROP 0 LAST $SEC 1
J 0
(-1675 2325);
DISPLAY 0.680851 (-1675 2325);
PAINT MONO (-1675 2325);
DISPLAY INVISIBLE (-1675 2325);
FORCEPROP 0 LAST CDS_SEC 1
J 0
(-1675 2325);
DISPLAY 0.680851 (-1675 2325);
DISPLAY INVISIBLE (-1675 2325);
FORCEADD OFFPAGE..4
R 2
(-2750 2175);
FORCEPROP 2 LAST $XR0 54 
J 0
(-3001 2175);
DISPLAY 0.638298 (-3001 2175);
PAINT MONO (-3001 2175);
FORCEPROP 1 LAST COMMENT_BODY TRUE
J 2
(-2725 2075);
DISPLAY 0.872340 (-2725 2075);
PAINT PEACH (-2725 2075);
DISPLAY INVISIBLE (-2725 2075);
FORCEPROP 1 LAST OFFPAGE TRUE
J 2
(-3075 2050);
DISPLAY 0.872340 (-3075 2050);
PAINT GREEN (-3075 2050);
DISPLAY INVISIBLE (-3075 2050);
FORCEPROP 2 LAST CDS_LIB standard
J 0
(-2750 2175);
DISPLAY INVISIBLE (-2750 2175);
FORCEPROP 2 LAST PATH I103
J 0
(-2950 2225);
DISPLAY 0.680851 (-2950 2225);
DISPLAY INVISIBLE (-2950 2225);
FORCEADD Q_CAP..1
(1850 2000);
FORCEPROP 1 LAST TOLERANCE 10%
J 0
(1900 1950);
DISPLAY 0.510638 (1900 1950);
PAINT SKYBLUE (1900 1950);
FORCEPROP 1 LAST VOLTAGE 25V
J 0
(1900 2000);
DISPLAY 0.510638 (1900 2000);
PAINT SKYBLUE (1900 2000);
FORCEPROP 1 LAST MATERIAL X6S
J 0
(1900 1900);
DISPLAY 0.510638 (1900 1900);
PAINT SKYBLUE (1900 1900);
FORCEPROP 1 LAST VALUE 10UF
J 0
(1900 2050);
DISPLAY 0.510638 (1900 2050);
PAINT SKYBLUE (1900 2050);
FORCEPROP 1 LAST PART_NUMBER CH6104KEA00
J 0
(1900 1850);
DISPLAY 0.510638 (1900 1850);
PAINT WHITE (1900 1850);
FORCEPROP 1 LAST PACK_TYPE C0805
J 0
(1900 1800);
DISPLAY 0.510638 (1900 1800);
PAINT SKYBLUE (1900 1800);
FORCEPROP 2 LAST CDS_LIB pure_quanta
J 0
(1850 2000);
DISPLAY INVISIBLE (1850 2000);
FORCEPROP 1 LAST PATH I104
J 0
(1900 2150);
DISPLAY 0.978723 (1900 2150);
PAINT WHITE (1900 2150);
DISPLAY INVISIBLE (1900 2150);
FORCEPROP 1 LAST $LOCATION C142
J 0
(1900 2100);
DISPLAY 0.978723 (1900 2100);
FORCEPROP 1 LASTPIN (1850 2100) $PN 1
J 0
(1860 2080);
DISPLAY 0.787234 (1860 2080);
PAINT MONO (1860 2080);
FORCEPROP 1 LASTPIN (1850 1900) $PN 2
J 0
(1860 1880);
DISPLAY 0.787234 (1860 1880);
PAINT MONO (1860 1880);
FORCEPROP 0 LAST CDS_LOCATION C142
J 0
(1900 2150);
DISPLAY 0.680851 (1900 2150);
DISPLAY INVISIBLE (1900 2150);
FORCEPROP 0 LAST $SEC 1
J 0
(1900 2150);
DISPLAY 0.680851 (1900 2150);
PAINT MONO (1900 2150);
DISPLAY INVISIBLE (1900 2150);
FORCEPROP 0 LAST CDS_SEC 1
J 0
(1900 2150);
DISPLAY 0.680851 (1900 2150);
DISPLAY INVISIBLE (1900 2150);
FORCEADD Q_CAP..1
(2500 2000);
FORCEPROP 1 LAST TOLERANCE 10%
J 0
(2550 1950);
DISPLAY 0.510638 (2550 1950);
PAINT SKYBLUE (2550 1950);
FORCEPROP 1 LAST PACK_TYPE 0402
J 0
(2550 1800);
DISPLAY 0.510638 (2550 1800);
PAINT SKYBLUE (2550 1800);
FORCEPROP 1 LAST VALUE 0.1UF
J 0
(2550 2050);
DISPLAY 0.510638 (2550 2050);
PAINT SKYBLUE (2550 2050);
FORCEPROP 1 LAST MATERIAL X7R
J 0
(2550 1900);
DISPLAY 0.510638 (2550 1900);
PAINT SKYBLUE (2550 1900);
FORCEPROP 1 LAST VOLTAGE 25V
J 0
(2550 2000);
DISPLAY 0.510638 (2550 2000);
PAINT SKYBLUE (2550 2000);
FORCEPROP 1 LAST PART_NUMBER CH4104K1B00
J 0
(2550 1850);
DISPLAY 0.510638 (2550 1850);
PAINT WHITE (2550 1850);
FORCEPROP 1 LAST PATH I105
J 0
(2550 2150);
DISPLAY 0.978723 (2550 2150);
PAINT WHITE (2550 2150);
DISPLAY INVISIBLE (2550 2150);
FORCEPROP 2 LAST CDS_LIB pure_quanta
J 0
(2500 2000);
DISPLAY INVISIBLE (2500 2000);
FORCEPROP 1 LAST $LOCATION C294
J 0
(2550 2100);
DISPLAY 0.978723 (2550 2100);
FORCEPROP 1 LASTPIN (2500 2100) $PN 1
J 0
(2510 2080);
DISPLAY 0.787234 (2510 2080);
PAINT MONO (2510 2080);
FORCEPROP 1 LASTPIN (2500 1900) $PN 2
J 0
(2510 1880);
DISPLAY 0.787234 (2510 1880);
PAINT MONO (2510 1880);
FORCEPROP 0 LAST CDS_LOCATION C294
J 0
(2550 2150);
DISPLAY 0.680851 (2550 2150);
DISPLAY INVISIBLE (2550 2150);
FORCEPROP 0 LAST $SEC 1
J 0
(2550 2150);
DISPLAY 0.680851 (2550 2150);
PAINT MONO (2550 2150);
DISPLAY INVISIBLE (2550 2150);
FORCEPROP 0 LAST CDS_SEC 1
J 0
(2550 2150);
DISPLAY 0.680851 (2550 2150);
DISPLAY INVISIBLE (2550 2150);
FORCEADD Q_CAP..1
(1050 3025);
FORCEPROP 1 LAST TOLERANCE 10%
J 0
(1100 2975);
DISPLAY 0.510638 (1100 2975);
PAINT SKYBLUE (1100 2975);
FORCEPROP 1 LAST MATERIAL X6S
J 0
(1100 2925);
DISPLAY 0.510638 (1100 2925);
PAINT SKYBLUE (1100 2925);
FORCEPROP 1 LAST VOLTAGE 25V
J 0
(1100 3025);
DISPLAY 0.510638 (1100 3025);
PAINT SKYBLUE (1100 3025);
FORCEPROP 1 LAST VALUE 10UF
J 0
(1100 3075);
DISPLAY 0.510638 (1100 3075);
PAINT SKYBLUE (1100 3075);
FORCEPROP 1 LAST PART_NUMBER CH6104KEA00
J 0
(1100 2875);
DISPLAY 0.510638 (1100 2875);
PAINT WHITE (1100 2875);
FORCEPROP 1 LAST PACK_TYPE C0805
J 0
(1100 2825);
DISPLAY 0.510638 (1100 2825);
PAINT SKYBLUE (1100 2825);
FORCEPROP 1 LAST PATH I106
J 0
(1100 3175);
DISPLAY 0.978723 (1100 3175);
PAINT WHITE (1100 3175);
DISPLAY INVISIBLE (1100 3175);
FORCEPROP 2 LAST CDS_LIB pure_quanta
J 0
(1050 3025);
DISPLAY INVISIBLE (1050 3025);
FORCEPROP 1 LAST $LOCATION C293
J 0
(1100 3125);
DISPLAY 0.978723 (1100 3125);
FORCEPROP 1 LASTPIN (1050 3125) $PN 1
J 0
(1060 3105);
DISPLAY 0.787234 (1060 3105);
PAINT MONO (1060 3105);
FORCEPROP 1 LASTPIN (1050 2925) $PN 2
J 0
(1060 2905);
DISPLAY 0.787234 (1060 2905);
PAINT MONO (1060 2905);
FORCEPROP 0 LAST CDS_LOCATION C293
J 0
(1100 3175);
DISPLAY 0.680851 (1100 3175);
DISPLAY INVISIBLE (1100 3175);
FORCEPROP 0 LAST $SEC 1
J 0
(1100 3175);
DISPLAY 0.680851 (1100 3175);
PAINT MONO (1100 3175);
DISPLAY INVISIBLE (1100 3175);
FORCEPROP 0 LAST CDS_SEC 1
J 0
(1100 3175);
DISPLAY 0.680851 (1100 3175);
DISPLAY INVISIBLE (1100 3175);
FORCEADD Q_CAP..1
(-1000 2850);
FORCEPROP 1 LAST VALUE 1UF
J 0
(-950 2900);
DISPLAY 0.510638 (-950 2900);
PAINT SKYBLUE (-950 2900);
FORCEPROP 1 LAST VOLTAGE 25V
J 0
(-950 2850);
DISPLAY 0.510638 (-950 2850);
PAINT SKYBLUE (-950 2850);
FORCEPROP 1 LAST TOLERANCE 10%
J 0
(-950 2800);
DISPLAY 0.510638 (-950 2800);
PAINT SKYBLUE (-950 2800);
FORCEPROP 1 LAST MATERIAL X6S
J 0
(-950 2750);
DISPLAY 0.510638 (-950 2750);
PAINT SKYBLUE (-950 2750);
FORCEPROP 1 LAST PART_NUMBER CH5104KEB02
J 0
(-950 2700);
DISPLAY 0.510638 (-950 2700);
PAINT WHITE (-950 2700);
FORCEPROP 1 LAST PACK_TYPE C0402
J 0
(-950 2650);
DISPLAY 0.510638 (-950 2650);
PAINT SKYBLUE (-950 2650);
FORCEPROP 1 LAST PATH I107
J 0
(-950 3000);
DISPLAY 0.978723 (-950 3000);
PAINT WHITE (-950 3000);
DISPLAY INVISIBLE (-950 3000);
FORCEPROP 2 LAST CDS_LIB pure_quanta
J 0
(-1000 2850);
DISPLAY INVISIBLE (-1000 2850);
FORCEPROP 1 LAST $LOCATION C292
J 0
(-950 2950);
DISPLAY 0.978723 (-950 2950);
FORCEPROP 1 LASTPIN (-1000 2950) $PN 1
J 0
(-990 2930);
DISPLAY 0.787234 (-990 2930);
PAINT MONO (-990 2930);
FORCEPROP 1 LASTPIN (-1000 2750) $PN 2
J 0
(-990 2730);
DISPLAY 0.787234 (-990 2730);
PAINT MONO (-990 2730);
FORCEPROP 0 LAST CDS_LOCATION C292
J 0
(-950 3000);
DISPLAY 0.680851 (-950 3000);
DISPLAY INVISIBLE (-950 3000);
FORCEPROP 0 LAST $SEC 1
J 0
(-950 3000);
DISPLAY 0.680851 (-950 3000);
PAINT MONO (-950 3000);
DISPLAY INVISIBLE (-950 3000);
FORCEPROP 0 LAST CDS_SEC 1
J 0
(-950 3000);
DISPLAY 0.680851 (-950 3000);
DISPLAY INVISIBLE (-950 3000);
FORCEADD Q_RES..2
(-725 1850);
FORCEPROP 1 LAST PACK_TYPE 0402LF
J 0
(-685 1675);
DISPLAY 0.510638 (-685 1675);
PAINT SKYBLUE (-685 1675);
FORCEPROP 1 LAST TOLERANCE 1%
J 0
(-680 1875);
DISPLAY 0.510638 (-680 1875);
PAINT SKYBLUE (-680 1875);
FORCEPROP 1 LAST VALUE 10K
J 0
(-680 1925);
DISPLAY 0.510638 (-680 1925);
PAINT SKYBLUE (-680 1925);
FORCEPROP 1 LAST PART_NUMBER CS31002FB08
J 0
(-685 1725);
DISPLAY 0.510638 (-685 1725);
PAINT WHITE (-685 1725);
FORCEPROP 1 LAST MATERIAL CHIP
J 0
(-685 1775);
DISPLAY 0.510638 (-685 1775);
PAINT SKYBLUE (-685 1775);
FORCEPROP 1 LAST WATTAGE 1/16W
J 0
(-685 1825);
DISPLAY 0.510638 (-685 1825);
PAINT SKYBLUE (-685 1825);
FORCEPROP 2 LAST CDS_LIB pure_quanta
J 0
(-725 1850);
DISPLAY INVISIBLE (-725 1850);
FORCEPROP 1 LAST PATH I108
J 0
(-675 2025);
DISPLAY 0.978723 (-675 2025);
PAINT WHITE (-675 2025);
DISPLAY INVISIBLE (-675 2025);
FORCEPROP 1 LAST $LOCATION R406
J 0
(-680 1975);
DISPLAY 0.978723 (-680 1975);
FORCEPROP 1 LASTPIN (-725 1950) $PN 1
J 0
(-720 1912);
DISPLAY 0.787234 (-720 1912);
PAINT MONO (-720 1912);
FORCEPROP 1 LASTPIN (-725 1750) $PN 2
J 0
(-720 1760);
DISPLAY 0.787234 (-720 1760);
PAINT MONO (-720 1760);
FORCEPROP 0 LAST CDS_LOCATION R406
J 0
(-675 2025);
DISPLAY 0.680851 (-675 2025);
DISPLAY INVISIBLE (-675 2025);
FORCEPROP 0 LAST $SEC 1
J 0
(-675 2025);
DISPLAY 0.680851 (-675 2025);
PAINT MONO (-675 2025);
DISPLAY INVISIBLE (-675 2025);
FORCEPROP 0 LAST CDS_SEC 1
J 0
(-675 2025);
DISPLAY 0.680851 (-675 2025);
DISPLAY INVISIBLE (-675 2025);
FORCEADD OFFPAGE..4
R 2
(-775 -200);
FORCEPROP 2 LAST $XR3 55 
J 0
(-1266 -200);
DISPLAY 0.638298 (-1266 -200);
PAINT MONO (-1266 -200);
FORCEPROP 2 LAST $XR2 52 
J 0
(-1176 -200);
DISPLAY 0.638298 (-1176 -200);
PAINT MONO (-1176 -200);
FORCEPROP 2 LAST $XR1 35 
J 0
(-1086 -200);
DISPLAY 0.638298 (-1086 -200);
PAINT MONO (-1086 -200);
FORCEPROP 2 LAST $XR0 51 
J 0
(-996 -200);
DISPLAY 0.638298 (-996 -200);
PAINT MONO (-996 -200);
FORCEPROP 2 LAST $XR4 56 
J 0
(-1356 -200);
DISPLAY 0.638298 (-1356 -200);
PAINT MONO (-1356 -200);
FORCEPROP 2 LAST PATH I110
J 0
(-1025 -150);
DISPLAY 0.680851 (-1025 -150);
DISPLAY INVISIBLE (-1025 -150);
FORCEPROP 2 LAST CDS_LIB standard
J 0
(-775 -200);
DISPLAY INVISIBLE (-775 -200);
FORCEPROP 1 LAST OFFPAGE TRUE
J 2
(-1100 -325);
DISPLAY 0.872340 (-1100 -325);
PAINT GREEN (-1100 -325);
DISPLAY INVISIBLE (-1100 -325);
FORCEPROP 1 LAST COMMENT_BODY TRUE
J 2
(-750 -300);
DISPLAY 0.872340 (-750 -300);
PAINT PEACH (-750 -300);
DISPLAY INVISIBLE (-750 -300);
FORCEADD UNIVERSAL_GND..1
(350 -950);
FORCEPROP 3 LASTPIN (350 -900) SIG_NAME GND\g
J 0
(360 -890);
DISPLAY 0.659574 (360 -890);
PAINT MONO (360 -890);
DISPLAY INVISIBLE (360 -890);
FORCEPROP 2 LAST CDS_LIB logical_power
J 0
(350 -950);
DISPLAY INVISIBLE (350 -950);
FORCEPROP 1 LAST PATH I111
J 0
(425 -950);
DISPLAY 0.872340 (425 -950);
PAINT AQUA (425 -950);
DISPLAY INVISIBLE (425 -950);
FORCEPROP 1 LAST HDL_POWER GND
J 1
(375 -1025);
DISPLAY 0.702128 (375 -1025);
PAINT GREEN (375 -1025);
DISPLAY INVISIBLE (375 -1025);
FORCEADD Q_CAP..1
R 2
(1500 50);
FORCEPROP 1 LAST VOLTAGE 25V
J 2
(1450 25);
DISPLAY 0.510638 (1450 25);
PAINT SKYBLUE (1450 25);
FORCEPROP 1 LAST VALUE 0.1UF
J 2
(1450 75);
DISPLAY 0.510638 (1450 75);
PAINT SKYBLUE (1450 75);
FORCEPROP 1 LAST TOLERANCE 10%
J 2
(1450 -25);
DISPLAY 0.510638 (1450 -25);
PAINT SKYBLUE (1450 -25);
FORCEPROP 1 LAST MATERIAL X7R
J 2
(1450 -75);
DISPLAY 0.510638 (1450 -75);
PAINT SKYBLUE (1450 -75);
FORCEPROP 1 LAST PACK_TYPE 0402
J 2
(1450 -125);
DISPLAY 0.510638 (1450 -125);
PAINT SKYBLUE (1450 -125);
FORCEPROP 1 LAST PART_NUMBER CH4104K1B00
J 2
(1450 -175);
DISPLAY 0.510638 (1450 -175);
PAINT WHITE (1450 -175);
FORCEPROP 2 LAST CDS_LIB pure_quanta
J 0
(1500 50);
DISPLAY INVISIBLE (1500 50);
FORCEPROP 1 LAST PATH I112
J 2
(1450 200);
DISPLAY 0.978723 (1450 200);
PAINT WHITE (1450 200);
DISPLAY INVISIBLE (1450 200);
FORCEPROP 1 LAST $LOCATION C298
J 2
(1450 150);
DISPLAY 0.787234 (1450 150);
FORCEPROP 1 LASTPIN (1500 150) $PN 1
J 2
(1490 130);
DISPLAY 0.787234 (1490 130);
PAINT MONO (1490 130);
FORCEPROP 1 LASTPIN (1500 -50) $PN 2
J 2
(1490 -70);
DISPLAY 0.787234 (1490 -70);
PAINT MONO (1490 -70);
FORCEPROP 0 LAST CDS_LOCATION C298
J 0
(1450 200);
DISPLAY 0.680851 (1450 200);
DISPLAY INVISIBLE (1450 200);
FORCEPROP 0 LAST $SEC 1
J 0
(1450 200);
DISPLAY 0.680851 (1450 200);
PAINT MONO (1450 200);
DISPLAY INVISIBLE (1450 200);
FORCEPROP 0 LAST CDS_SEC 1
J 0
(1450 200);
DISPLAY 0.680851 (1450 200);
DISPLAY INVISIBLE (1450 200);
FORCEADD UNIVERSAL_GND..1
(1500 -175);
FORCEPROP 3 LASTPIN (1500 -125) SIG_NAME GND\g
J 0
(1510 -115);
DISPLAY 0.659574 (1510 -115);
PAINT MONO (1510 -115);
DISPLAY INVISIBLE (1510 -115);
FORCEPROP 2 LAST CDS_LIB logical_power
J 0
(1500 -175);
DISPLAY INVISIBLE (1500 -175);
FORCEPROP 1 LAST PATH I114
J 0
(1575 -175);
DISPLAY 0.872340 (1575 -175);
PAINT AQUA (1575 -175);
DISPLAY INVISIBLE (1575 -175);
FORCEPROP 1 LAST HDL_POWER GND
J 1
(1525 -250);
DISPLAY 0.702128 (1525 -250);
PAINT GREEN (1525 -250);
DISPLAY INVISIBLE (1525 -250);
FORCEADD MC74VHC1G32DTT1G..1
(975 -600);
FORCEPROP 1 LAST MATERIAL IC
J 0
(580 -318);
DISPLAY 0.723404 (580 -318);
PAINT GREEN (580 -318);
FORCEPROP 2 LAST PART_TYPE SMLF
J 0
(575 -25);
DISPLAY 0.680851 (575 -25);
FORCEPROP 2 LAST VALUE MC74VHC1G32DTT1G
J 0
(575 -75);
DISPLAY 0.680851 (575 -75);
FORCEPROP 1 LAST PART_NUMBER AL001G32031
J 0
(580 -191);
DISPLAY 0.723404 (580 -191);
PAINT GREEN (580 -191);
FORCEPROP 1 LAST NEEDS_NO_SIZE TRUE
J 0
(975 -600);
DISPLAY 0.723404 (975 -600);
PAINT GREEN (975 -600);
DISPLAY INVISIBLE (975 -600);
FORCEPROP 1 LAST CDS_LMAN_SYM_OUTLINE -400,275,400,-275
J 0
(975 -600);
DISPLAY 0.468085 (975 -600);
PAINT GREEN (975 -600);
DISPLAY INVISIBLE (975 -600);
FORCEPROP 2 LAST CDS_LIB pure_quanta
J 0
(975 -600);
DISPLAY INVISIBLE (975 -600);
FORCEPROP 1 LAST PATH I116
J 0
(975 -600);
DISPLAY 0.723404 (975 -600);
PAINT GREEN (975 -600);
DISPLAY INVISIBLE (975 -600);
FORCEPROP 1 LAST $LOCATION U49
J 0
(575 -250);
DISPLAY 0.723404 (575 -250);
PAINT GREEN (575 -250);
FORCEPROP 0 LASTPIN (425 -775) $PN 3
J 2
(415 -765);
DISPLAY 0.680851 (415 -765);
PAINT MONO (415 -765);
FORCEPROP 0 LASTPIN (425 -625) $PN 2
J 2
(415 -615);
DISPLAY 0.680851 (415 -615);
PAINT MONO (415 -615);
FORCEPROP 0 LASTPIN (425 -425) $PN 1
J 2
(415 -415);
DISPLAY 0.680851 (415 -415);
PAINT MONO (415 -415);
FORCEPROP 0 LASTPIN (1525 -775) $PN 4
J 0
(1535 -765);
DISPLAY 0.680851 (1535 -765);
PAINT MONO (1535 -765);
FORCEPROP 0 LASTPIN (1525 -425) $PN 5
J 0
(1535 -415);
DISPLAY 0.680851 (1535 -415);
PAINT MONO (1535 -415);
FORCEPROP 0 LAST CDS_LOCATION U49
J 0
(575 25);
DISPLAY 0.680851 (575 25);
DISPLAY INVISIBLE (575 25);
FORCEPROP 0 LAST $SEC 1
J 0
(575 25);
DISPLAY 0.680851 (575 25);
PAINT MONO (575 25);
DISPLAY INVISIBLE (575 25);
FORCEPROP 0 LAST CDS_SEC 1
J 0
(575 25);
DISPLAY 0.680851 (575 25);
DISPLAY INVISIBLE (575 25);
FORCEADD OFFPAGE..4
R 2
(-1500 -625);
FORCEPROP 2 LAST $XR2 55 
J 0
(-1931 -625);
DISPLAY 0.638298 (-1931 -625);
PAINT MONO (-1931 -625);
FORCEPROP 2 LAST $XR1 36 
J 0
(-1841 -625);
DISPLAY 0.638298 (-1841 -625);
PAINT MONO (-1841 -625);
FORCEPROP 2 LAST $XR0 52 
J 0
(-1751 -625);
DISPLAY 0.638298 (-1751 -625);
PAINT MONO (-1751 -625);
FORCEPROP 2 LAST PATH I117
J 0
(-1750 -575);
DISPLAY 0.680851 (-1750 -575);
DISPLAY INVISIBLE (-1750 -575);
FORCEPROP 1 LAST COMMENT_BODY TRUE
J 2
(-1475 -725);
DISPLAY 0.872340 (-1475 -725);
PAINT PEACH (-1475 -725);
DISPLAY INVISIBLE (-1475 -725);
FORCEPROP 1 LAST OFFPAGE TRUE
J 2
(-1825 -750);
DISPLAY 0.872340 (-1825 -750);
PAINT GREEN (-1825 -750);
DISPLAY INVISIBLE (-1825 -750);
FORCEPROP 2 LAST CDS_LIB standard
J 0
(-1500 -625);
DISPLAY INVISIBLE (-1500 -625);
FORCEADD Q_CAP..1
(-375 -825);
FORCEPROP 1 LAST VALUE 1UF
J 0
(-325 -775);
DISPLAY 0.510638 (-325 -775);
PAINT SKYBLUE (-325 -775);
FORCEPROP 1 LAST VOLTAGE 25V
J 0
(-325 -825);
DISPLAY 0.510638 (-325 -825);
PAINT SKYBLUE (-325 -825);
FORCEPROP 1 LAST PART_NUMBER CH5104KEB02
J 0
(-325 -975);
DISPLAY 0.510638 (-325 -975);
PAINT WHITE (-325 -975);
FORCEPROP 1 LAST PACK_TYPE C0402
J 0
(-325 -1025);
DISPLAY 0.510638 (-325 -1025);
PAINT SKYBLUE (-325 -1025);
FORCEPROP 1 LAST MATERIAL X6S
J 0
(-325 -925);
DISPLAY 0.510638 (-325 -925);
PAINT SKYBLUE (-325 -925);
FORCEPROP 1 LAST TOLERANCE 10%
J 0
(-325 -875);
DISPLAY 0.510638 (-325 -875);
PAINT SKYBLUE (-325 -875);
FORCEPROP 1 LAST PATH I130
J 0
(-325 -675);
DISPLAY 0.978723 (-325 -675);
PAINT WHITE (-325 -675);
DISPLAY INVISIBLE (-325 -675);
FORCEPROP 2 LAST CDS_LIB pure_quanta
J 0
(-375 -825);
DISPLAY INVISIBLE (-375 -825);
FORCEPROP 1 LAST $LOCATION C310
J 0
(-325 -725);
DISPLAY 0.702128 (-325 -725);
PAINT YELLOW (-325 -725);
FORCEPROP 1 LASTPIN (-375 -725) $PN 1
J 0
(-365 -745);
DISPLAY 0.787234 (-365 -745);
PAINT MONO (-365 -745);
FORCEPROP 1 LASTPIN (-375 -925) $PN 2
J 0
(-365 -945);
DISPLAY 0.787234 (-365 -945);
PAINT MONO (-365 -945);
FORCEPROP 0 LAST CDS_LOCATION C310
J 0
(-325 -675);
DISPLAY 0.680851 (-325 -675);
DISPLAY INVISIBLE (-325 -675);
FORCEPROP 0 LAST $SEC 1
J 0
(-325 -675);
DISPLAY 0.680851 (-325 -675);
PAINT MONO (-325 -675);
DISPLAY INVISIBLE (-325 -675);
FORCEPROP 0 LAST CDS_SEC 1
J 0
(-325 -675);
DISPLAY 0.680851 (-325 -675);
DISPLAY INVISIBLE (-325 -675);
FORCEADD UNIVERSAL_GND..1
(-375 -1050);
FORCEPROP 3 LASTPIN (-375 -1000) SIG_NAME GND\g
J 0
(-365 -990);
DISPLAY 0.659574 (-365 -990);
PAINT MONO (-365 -990);
DISPLAY INVISIBLE (-365 -990);
FORCEPROP 1 LAST PATH I131
J 0
(-300 -1050);
DISPLAY 0.872340 (-300 -1050);
PAINT AQUA (-300 -1050);
DISPLAY INVISIBLE (-300 -1050);
FORCEPROP 1 LAST HDL_POWER GND
J 1
(-350 -1125);
DISPLAY 0.702128 (-350 -1125);
PAINT GREEN (-350 -1125);
DISPLAY INVISIBLE (-350 -1125);
FORCEPROP 2 LAST CDS_LIB logical_power
J 0
(-375 -1050);
DISPLAY INVISIBLE (-375 -1050);
FORCEADD Q_RES..1
(-625 -625);
FORCEPROP 1 LAST PACK_TYPE 0402LF
J 0
(-600 -575);
DISPLAY 0.638298 (-600 -575);
FORCEPROP 1 LAST PART_NUMBER CS11002FB07
J 0
(-675 -525);
DISPLAY 0.638298 (-675 -525);
FORCEPROP 1 LAST TOLERANCE 1%
J 0
(-600 -675);
DISPLAY 0.638298 (-600 -675);
FORCEPROP 1 LAST VALUE 100
J 2
(-625 -675);
DISPLAY 0.638298 (-625 -675);
FORCEPROP 1 LAST MATERIAL CHIP
J 0
(-600 -725);
DISPLAY 0.638298 (-600 -725);
FORCEPROP 1 LAST WATTAGE 1/16W
J 2
(-625 -725);
DISPLAY 0.638298 (-625 -725);
FORCEPROP 1 LAST PATH I132
J 0
(-675 -475);
DISPLAY 0.978723 (-675 -475);
PAINT WHITE (-675 -475);
DISPLAY INVISIBLE (-675 -475);
FORCEPROP 2 LAST CDS_LIB pure_quanta
J 0
(-625 -625);
DISPLAY INVISIBLE (-625 -625);
FORCEPROP 1 LAST $LOCATION R530
J 0
(-850 -575);
DISPLAY 0.787234 (-850 -575);
FORCEPROP 1 LASTPIN (-725 -625) $PN 1
J 0
(-713 -613);
DISPLAY 0.787234 (-713 -613);
PAINT MONO (-713 -613);
FORCEPROP 1 LASTPIN (-525 -625) $PN 2
J 0
(-563 -613);
DISPLAY 0.787234 (-563 -613);
PAINT MONO (-563 -613);
FORCEPROP 0 LAST CDS_LOCATION R530
J 0
(-675 -475);
DISPLAY 0.680851 (-675 -475);
DISPLAY INVISIBLE (-675 -475);
FORCEPROP 0 LAST $SEC 1
J 0
(-675 -475);
DISPLAY 0.680851 (-675 -475);
PAINT MONO (-675 -475);
DISPLAY INVISIBLE (-675 -475);
FORCEPROP 0 LAST CDS_SEC 1
J 0
(-675 -475);
DISPLAY 0.680851 (-675 -475);
DISPLAY INVISIBLE (-675 -475);
FORCEADD OFFPAGE..5
R 2
(2975 -775);
FORCEPROP 2 LAST $XR0 54 
J 0
(3164 -775);
DISPLAY 0.638298 (3164 -775);
PAINT MONO (3164 -775);
FORCEPROP 2 LAST CDS_LIB standard
J 0
(2975 -775);
DISPLAY INVISIBLE (2975 -775);
FORCEPROP 1 LAST OFFPAGE TRUE
J 2
(2650 -900);
DISPLAY 0.872340 (2650 -900);
PAINT GREEN (2650 -900);
DISPLAY INVISIBLE (2650 -900);
FORCEPROP 1 LAST COMMENT_BODY TRUE
J 2
(2875 -850);
DISPLAY 0.872340 (2875 -850);
PAINT PEACH (2875 -850);
DISPLAY INVISIBLE (2875 -850);
FORCEPROP 2 LAST PATH I136
J 0
(3175 -725);
DISPLAY 0.680851 (3175 -725);
DISPLAY INVISIBLE (3175 -725);
FORCEADD Q_RES..1
(-1625 2450);
FORCEPROP 1 LAST PACK_TYPE 0402LF
J 0
(-1675 2375);
DISPLAY 0.978723 (-1675 2375);
FORCEPROP 1 LAST WATTAGE 1/16W
J 2
(-1700 2375);
DISPLAY 0.978723 (-1700 2375);
FORCEPROP 1 LAST VALUE 0
J 2
(-1775 2450);
DISPLAY 0.978723 (-1775 2450);
FORCEPROP 1 LAST TOLERANCE 5%
J 0
(-2025 2375);
DISPLAY 0.978723 (-2025 2375);
FORCEPROP 1 LAST MATERIAL EMPTY
J 0
(-1875 2500);
DISPLAY 0.978723 (-1875 2500);
PAINT RED (-1875 2500);
FORCEPROP 1 LAST PART_NUMBER CS00002JB13
J 0
(-1850 2550);
DISPLAY 0.978723 (-1850 2550);
FORCEPROP 2 LAST CDS_LIB pure_quanta
J 0
(-1625 2450);
DISPLAY INVISIBLE (-1625 2450);
FORCEPROP 1 LAST PATH I137
J 0
(-1675 2600);
DISPLAY 0.978723 (-1675 2600);
PAINT WHITE (-1675 2600);
DISPLAY INVISIBLE (-1675 2600);
FORCEPROP 1 LAST $LOCATION R875
J 0
(-1625 2500);
DISPLAY 0.978723 (-1625 2500);
FORCEPROP 1 LASTPIN (-1725 2450) $PN 1
J 0
(-1713 2462);
DISPLAY 0.787234 (-1713 2462);
PAINT MONO (-1713 2462);
FORCEPROP 1 LASTPIN (-1525 2450) $PN 2
J 0
(-1563 2462);
DISPLAY 0.787234 (-1563 2462);
PAINT MONO (-1563 2462);
FORCEPROP 0 LAST CDS_LOCATION R875
J 0
(-1850 2600);
DISPLAY 0.680851 (-1850 2600);
DISPLAY INVISIBLE (-1850 2600);
FORCEPROP 0 LAST $SEC 1
J 0
(-1850 2600);
DISPLAY 0.680851 (-1850 2600);
PAINT MONO (-1850 2600);
DISPLAY INVISIBLE (-1850 2600);
FORCEPROP 0 LAST CDS_SEC 1
J 0
(-1850 2600);
DISPLAY 0.680851 (-1850 2600);
DISPLAY INVISIBLE (-1850 2600);
FORCEADD OFFPAGE..4
R 2
(-2750 2450);
FORCEPROP 2 LAST $XR0 53 
J 0
(-3001 2450);
DISPLAY 0.638298 (-3001 2450);
PAINT MONO (-3001 2450);
FORCEPROP 2 LAST PATH I138
J 0
(-3000 2500);
DISPLAY 0.680851 (-3000 2500);
DISPLAY INVISIBLE (-3000 2500);
FORCEPROP 2 LAST CDS_LIB standard
J 0
(-2750 2450);
DISPLAY INVISIBLE (-2750 2450);
FORCEPROP 1 LAST OFFPAGE TRUE
J 2
(-3075 2325);
DISPLAY 0.872340 (-3075 2325);
PAINT GREEN (-3075 2325);
DISPLAY INVISIBLE (-3075 2325);
FORCEPROP 1 LAST COMMENT_BODY TRUE
J 2
(-2725 2350);
DISPLAY 0.872340 (-2725 2350);
PAINT PEACH (-2725 2350);
DISPLAY INVISIBLE (-2725 2350);
FORCEADD Q_RES..1
(-2025 1800);
FORCEPROP 1 LAST MATERIAL EMPTY
J 0
(-1775 1800);
DISPLAY 0.510638 (-1775 1800);
PAINT RED (-1775 1800);
FORCEPROP 1 LAST VALUE 0
J 2
(-1800 1800);
DISPLAY 0.510638 (-1800 1800);
PAINT SKYBLUE (-1800 1800);
FORCEPROP 1 LAST PACK_TYPE 0402LF
J 0
(-2100 1750);
DISPLAY 0.510638 (-2100 1750);
PAINT SKYBLUE (-2100 1750);
FORCEPROP 1 LAST PART_NUMBER CS00002JB13
J 0
(-2125 1850);
DISPLAY 0.510638 (-2125 1850);
PAINT WHITE (-2125 1850);
FORCEPROP 1 LAST WATTAGE 1/16W
J 2
(-2050 1650);
DISPLAY 0.510638 (-2050 1650);
PAINT SKYBLUE (-2050 1650);
DISPLAY INVISIBLE (-2050 1650);
FORCEPROP 1 LAST TOLERANCE 5%
J 0
(-2025 1700);
DISPLAY 0.510638 (-2025 1700);
PAINT SKYBLUE (-2025 1700);
DISPLAY INVISIBLE (-2025 1700);
FORCEPROP 1 LAST PATH I139
J 0
(-2075 1950);
DISPLAY 0.978723 (-2075 1950);
PAINT WHITE (-2075 1950);
DISPLAY INVISIBLE (-2075 1950);
FORCEPROP 2 LAST CDS_LIB pure_quanta
J 0
(-2025 1800);
DISPLAY INVISIBLE (-2025 1800);
FORCEPROP 1 LAST $LOCATION R874
J 0
(-2275 1800);
DISPLAY 0.702128 (-2275 1800);
PAINT YELLOW (-2275 1800);
FORCEPROP 1 LASTPIN (-2125 1800) $PN 1
J 0
(-2113 1812);
DISPLAY 0.787234 (-2113 1812);
PAINT MONO (-2113 1812);
FORCEPROP 1 LASTPIN (-1925 1800) $PN 2
J 0
(-1963 1812);
DISPLAY 0.787234 (-1963 1812);
PAINT MONO (-1963 1812);
FORCEPROP 0 LAST CDS_LOCATION R874
J 0
(-2125 1875);
DISPLAY 0.680851 (-2125 1875);
DISPLAY INVISIBLE (-2125 1875);
FORCEPROP 0 LAST $SEC 1
J 0
(-2125 1875);
DISPLAY 0.680851 (-2125 1875);
PAINT MONO (-2125 1875);
DISPLAY INVISIBLE (-2125 1875);
FORCEPROP 0 LAST CDS_SEC 1
J 0
(-2125 1875);
DISPLAY 0.680851 (-2125 1875);
DISPLAY INVISIBLE (-2125 1875);
FORCEADD OFFPAGE..2
R 2
(-3075 1800);
FORCEPROP 2 LAST $XR0 52 
J 0
(-3329 1800);
DISPLAY 0.638298 (-3329 1800);
PAINT MONO (-3329 1800);
FORCEPROP 2 LAST PATH I140
J 0
(-3325 1850);
DISPLAY 0.680851 (-3325 1850);
DISPLAY INVISIBLE (-3325 1850);
FORCEPROP 2 LAST CDS_LIB standard
J 0
(-3075 1800);
DISPLAY INVISIBLE (-3075 1800);
FORCEPROP 1 LAST OFFPAGE TRUE
J 2
(-3400 1675);
DISPLAY 0.872340 (-3400 1675);
PAINT GREEN (-3400 1675);
DISPLAY INVISIBLE (-3400 1675);
FORCEPROP 1 LAST COMMENT_BODY TRUE
J 2
(-3030 1705);
DISPLAY 0.872340 (-3030 1705);
PAINT PEACH (-3030 1705);
DISPLAY INVISIBLE (-3030 1705);
FORCEADD UNIVERSAL_POWER..1
(1500 300);
FORCEPROP 3 LASTPIN (1500 250) SIG_NAME P3V3_LDO\g
J 0
(1510 260);
DISPLAY 0.659574 (1510 260);
PAINT MONO (1510 260);
DISPLAY INVISIBLE (1510 260);
FORCEPROP 1 LAST HDL_POWER P3V3_LDO
J 1
(1500 350);
DISPLAY 0.702128 (1500 350);
PAINT GREEN (1500 350);
FORCEPROP 1 LAST PATH I141
J 0
(1550 325);
DISPLAY 0.872340 (1550 325);
PAINT AQUA (1550 325);
DISPLAY INVISIBLE (1550 325);
FORCEPROP 2 LAST CDS_LIB logical_power
J 0
(1500 300);
DISPLAY INVISIBLE (1500 300);
FORCEADD UNIVERSAL_GND..1
(550 1350);
FORCEPROP 3 LASTPIN (550 1400) SIG_NAME GND\g
J 0
(560 1410);
DISPLAY 0.659574 (560 1410);
PAINT MONO (560 1410);
DISPLAY INVISIBLE (560 1410);
FORCEPROP 1 LAST PATH I54
J 0
(625 1350);
DISPLAY 0.872340 (625 1350);
PAINT AQUA (625 1350);
DISPLAY INVISIBLE (625 1350);
FORCEPROP 1 LAST HDL_POWER GND
J 1
(575 1275);
DISPLAY 0.702128 (575 1275);
PAINT GREEN (575 1275);
DISPLAY INVISIBLE (575 1275);
FORCEPROP 2 LAST CDS_LIB logical_power
J 0
(550 1350);
DISPLAY INVISIBLE (550 1350);
FORCEADD UNIVERSAL_GND..1
(-1000 2525);
FORCEPROP 3 LASTPIN (-1000 2575) SIG_NAME GND\g
J 0
(-990 2585);
DISPLAY 0.659574 (-990 2585);
PAINT MONO (-990 2585);
DISPLAY INVISIBLE (-990 2585);
FORCEPROP 1 LAST PATH I58
J 0
(-925 2525);
DISPLAY 0.872340 (-925 2525);
PAINT AQUA (-925 2525);
DISPLAY INVISIBLE (-925 2525);
FORCEPROP 1 LAST HDL_POWER GND
J 1
(-975 2450);
DISPLAY 0.702128 (-975 2450);
PAINT GREEN (-975 2450);
DISPLAY INVISIBLE (-975 2450);
FORCEPROP 2 LAST CDS_LIB logical_power
J 0
(-1000 2525);
DISPLAY INVISIBLE (-1000 2525);
FORCEADD VCCAUX15..1
(-1000 3275);
FORCEPROP 3 LASTPIN (-1000 3225) SIG_NAME P5V_AUX\g
J 0
(-990 3235);
DISPLAY 0.659574 (-990 3235);
PAINT MONO (-990 3235);
DISPLAY INVISIBLE (-990 3235);
FORCEPROP 1 LAST HDL_POWER P5V_AUX
J 1
(-1000 3325);
DISPLAY 0.702128 (-1000 3325);
PAINT GREEN (-1000 3325);
FORCEPROP 1 LAST PATH I60
J 0
(-950 3300);
DISPLAY 0.872340 (-950 3300);
PAINT AQUA (-950 3300);
DISPLAY INVISIBLE (-950 3300);
FORCEPROP 2 LAST CDS_LIB logical_power
J 0
(-1000 3275);
DISPLAY INVISIBLE (-1000 3275);
FORCEADD UNIVERSAL_GND..1
(1850 1575);
FORCEPROP 3 LASTPIN (1850 1625) SIG_NAME GND\g
J 0
(1860 1635);
DISPLAY 0.659574 (1860 1635);
PAINT MONO (1860 1635);
DISPLAY INVISIBLE (1860 1635);
FORCEPROP 1 LAST PATH I61
J 0
(1925 1575);
DISPLAY 0.872340 (1925 1575);
PAINT AQUA (1925 1575);
DISPLAY INVISIBLE (1925 1575);
FORCEPROP 1 LAST HDL_POWER GND
J 1
(1875 1500);
DISPLAY 0.702128 (1875 1500);
PAINT GREEN (1875 1500);
DISPLAY INVISIBLE (1875 1500);
FORCEPROP 2 LAST CDS_LIB logical_power
J 0
(1850 1575);
DISPLAY INVISIBLE (1850 1575);
FORCEADD UNIVERSAL_GND..1
(1050 2700);
FORCEPROP 3 LASTPIN (1050 2750) SIG_NAME GND\g
J 0
(1060 2760);
DISPLAY 0.659574 (1060 2760);
PAINT MONO (1060 2760);
DISPLAY INVISIBLE (1060 2760);
FORCEPROP 1 LAST PATH I62
J 0
(1125 2700);
DISPLAY 0.872340 (1125 2700);
PAINT AQUA (1125 2700);
DISPLAY INVISIBLE (1125 2700);
FORCEPROP 1 LAST HDL_POWER GND
J 1
(1075 2625);
DISPLAY 0.702128 (1075 2625);
PAINT GREEN (1075 2625);
DISPLAY INVISIBLE (1075 2625);
FORCEPROP 2 LAST CDS_LIB logical_power
J 0
(1050 2700);
DISPLAY INVISIBLE (1050 2700);
FORCEADD VCCAUX15..1
(1050 3450);
FORCEPROP 3 LASTPIN (1050 3400) SIG_NAME P3V3_AUX\g
J 0
(1060 3410);
DISPLAY 0.659574 (1060 3410);
PAINT MONO (1060 3410);
DISPLAY INVISIBLE (1060 3410);
FORCEPROP 1 LAST HDL_POWER P3V3_AUX
J 1
(1050 3500);
DISPLAY 0.702128 (1050 3500);
PAINT GREEN (1050 3500);
FORCEPROP 1 LAST PATH I64
J 0
(1100 3475);
DISPLAY 0.872340 (1100 3475);
PAINT AQUA (1100 3475);
DISPLAY INVISIBLE (1100 3475);
FORCEPROP 2 LAST CDS_LIB logical_power
J 0
(1050 3450);
DISPLAY INVISIBLE (1050 3450);
FORCEADD VCCAUX15..1
(3000 2400);
FORCEPROP 3 LASTPIN (3000 2350) SIG_NAME P1V8_AUX\g
J 0
(3010 2360);
DISPLAY 0.659574 (3010 2360);
PAINT MONO (3010 2360);
DISPLAY INVISIBLE (3010 2360);
FORCEPROP 1 LAST HDL_POWER P1V8_AUX
J 1
(3000 2450);
DISPLAY 0.702128 (3000 2450);
PAINT GREEN (3000 2450);
FORCEPROP 1 LAST PATH I67
J 0
(3050 2425);
DISPLAY 0.872340 (3050 2425);
PAINT AQUA (3050 2425);
DISPLAY INVISIBLE (3050 2425);
FORCEPROP 2 LAST CDS_LIB logical_power
J 0
(3000 2400);
DISPLAY INVISIBLE (3000 2400);
FORCEADD VCCAUX15..1
(-725 2025);
FORCEPROP 3 LASTPIN (-725 1975) SIG_NAME P3V3_AUX\g
J 0
(-715 1985);
DISPLAY 0.659574 (-715 1985);
PAINT MONO (-715 1985);
DISPLAY INVISIBLE (-715 1985);
FORCEPROP 1 LAST HDL_POWER P3V3_AUX
J 1
(-725 2075);
DISPLAY 0.702128 (-725 2075);
PAINT GREEN (-725 2075);
FORCEPROP 1 LAST PATH I89
J 0
(-675 2050);
DISPLAY 0.872340 (-675 2050);
PAINT AQUA (-675 2050);
DISPLAY INVISIBLE (-675 2050);
FORCEPROP 2 LAST CDS_LIB logical_power
J 0
(-725 2025);
DISPLAY INVISIBLE (-725 2025);
FORCEADD OFFPAGE..2
R 2
(-3075 1625);
FORCEPROP 2 LAST $XR2 55 
J 0
(-3509 1625);
DISPLAY 0.638298 (-3509 1625);
PAINT MONO (-3509 1625);
FORCEPROP 2 LAST $XR0 36 
J 0
(-3329 1625);
DISPLAY 0.638298 (-3329 1625);
PAINT MONO (-3329 1625);
FORCEPROP 2 LAST $XR1 52 
J 0
(-3419 1625);
DISPLAY 0.638298 (-3419 1625);
PAINT MONO (-3419 1625);
FORCEPROP 1 LAST COMMENT_BODY TRUE
J 2
(-3030 1530);
DISPLAY 0.872340 (-3030 1530);
PAINT PEACH (-3030 1530);
DISPLAY INVISIBLE (-3030 1530);
FORCEPROP 1 LAST OFFPAGE TRUE
J 2
(-3400 1500);
DISPLAY 0.872340 (-3400 1500);
PAINT GREEN (-3400 1500);
DISPLAY INVISIBLE (-3400 1500);
FORCEPROP 2 LAST CDS_LIB standard
J 0
(-3075 1625);
DISPLAY INVISIBLE (-3075 1625);
FORCEPROP 2 LAST PATH I90
J 0
(-3025 1700);
DISPLAY 1.021277 (-3025 1700);
DISPLAY INVISIBLE (-3025 1700);
FORCEADD RT9059GQW..1
(0 2125);
FORCEPROP 1 LAST MATERIAL IC
J 0
(-249 2690);
DISPLAY 0.510638 (-249 2690);
PAINT SKYBLUE (-249 2690);
FORCEPROP 2 LAST PART_TYPE SMLF
J 0
(-225 2925);
DISPLAY 0.510638 (-225 2925);
PAINT SKYBLUE (-225 2925);
FORCEPROP 2 LAST VALUE RT9059GQW
J 0
(-225 2875);
DISPLAY 0.510638 (-225 2875);
PAINT SKYBLUE (-225 2875);
FORCEPROP 1 LAST PART_NUMBER AL009059000
J 0
(-249 2760);
DISPLAY 0.510638 (-249 2760);
PAINT WHITE (-249 2760);
FORCEPROP 1 LAST PATH I96
J 2
(250 1575);
DISPLAY 0.723404 (250 1575);
PAINT GREEN (250 1575);
DISPLAY INVISIBLE (250 1575);
FORCEPROP 1 LAST PIN_NAMES_ROTATE True
J 0
(0 2125);
DISPLAY 0.723404 (0 2125);
PAINT GREEN (0 2125);
DISPLAY INVISIBLE (0 2125);
FORCEPROP 2 LAST CDS_LIB pure_quanta
J 0
(0 2125);
DISPLAY INVISIBLE (0 2125);
FORCEPROP 1 LAST CDS_LMAN_SYM_OUTLINE -250,550,250,-550
J 0
(0 2125);
DISPLAY 0.468085 (0 2125);
PAINT GREEN (0 2125);
DISPLAY INVISIBLE (0 2125);
FORCEPROP 1 LAST LOCATION U41
J 0
(-249 2820);
DISPLAY 0.702128 (-249 2820);
PAINT AQUA (-249 2820);
FORCEPROP 0 LASTPIN (400 1825) $PN 4
J 0
(410 1835);
DISPLAY 0.680851 (410 1835);
PAINT MONO (410 1835);
FORCEPROP 0 LASTPIN (-400 2175) $PN 6
J 2
(-410 2185);
DISPLAY 0.680851 (-410 2185);
PAINT MONO (-410 2185);
FORCEPROP 0 LASTPIN (400 1625) $PN TH
J 0
(410 1635);
DISPLAY 0.680851 (410 1635);
PAINT MONO (410 1635);
FORCEPROP 0 LASTPIN (-400 1625) $PN 5
J 2
(-410 1635);
DISPLAY 0.680851 (-410 1635);
PAINT MONO (-410 1635);
FORCEPROP 0 LASTPIN (-400 2625) $PN 10
J 2
(-410 2635);
DISPLAY 0.680851 (-410 2635);
PAINT MONO (-410 2635);
FORCEPROP 0 LASTPIN (400 2625) $PN 7
J 0
(410 2635);
DISPLAY 0.680851 (410 2635);
PAINT MONO (410 2635);
FORCEPROP 0 LASTPIN (400 2575) $PN 8
J 0
(410 2585);
DISPLAY 0.680851 (410 2585);
PAINT MONO (410 2585);
FORCEPROP 0 LASTPIN (400 2525) $PN 9
J 0
(410 2535);
DISPLAY 0.680851 (410 2535);
PAINT MONO (410 2535);
FORCEPROP 0 LASTPIN (400 2225) $PN 1
J 0
(410 2235);
DISPLAY 0.680851 (410 2235);
PAINT MONO (410 2235);
FORCEPROP 0 LASTPIN (400 2175) $PN 2
J 0
(410 2185);
DISPLAY 0.680851 (410 2185);
PAINT MONO (410 2185);
FORCEPROP 0 LASTPIN (400 2125) $PN 3
J 0
(410 2135);
DISPLAY 0.680851 (410 2135);
PAINT MONO (410 2135);
FORCEPROP 0 LAST $SEC 1
J 0
(-225 2950);
DISPLAY 0.680851 (-225 2950);
PAINT MONO (-225 2950);
DISPLAY INVISIBLE (-225 2950);
FORCEPROP 0 LAST CDS_SEC 1
J 0
(-225 2950);
DISPLAY 1.021277 (-225 2950);
DISPLAY INVISIBLE (-225 2950);
FORCEADD Q_RES..2
(975 1575);
FORCEPROP 1 LAST PACK_TYPE 0402LF
J 0
(1015 1400);
DISPLAY 0.510638 (1015 1400);
PAINT SKYBLUE (1015 1400);
FORCEPROP 1 LAST TOLERANCE 1%
J 0
(1020 1600);
DISPLAY 0.510638 (1020 1600);
PAINT SKYBLUE (1020 1600);
FORCEPROP 1 LAST VALUE 12K
J 0
(1020 1650);
DISPLAY 0.510638 (1020 1650);
PAINT SKYBLUE (1020 1650);
FORCEPROP 1 LAST WATTAGE 1/16W
J 0
(1015 1550);
DISPLAY 0.510638 (1015 1550);
PAINT SKYBLUE (1015 1550);
FORCEPROP 1 LAST MATERIAL CHIP
J 0
(1015 1500);
DISPLAY 0.510638 (1015 1500);
PAINT SKYBLUE (1015 1500);
FORCEPROP 1 LAST PART_NUMBER CS31202FB04
J 0
(1015 1450);
DISPLAY 0.510638 (1015 1450);
PAINT WHITE (1015 1450);
FORCEPROP 1 LAST PATH I97
J 0
(1025 1750);
DISPLAY 0.978723 (1025 1750);
PAINT WHITE (1025 1750);
DISPLAY INVISIBLE (1025 1750);
FORCEPROP 2 LAST CDS_LIB pure_quanta
J 0
(975 1575);
DISPLAY INVISIBLE (975 1575);
FORCEPROP 1 LAST LOCATION R832
J 0
(1020 1700);
DISPLAY 0.702128 (1020 1700);
PAINT YELLOW (1020 1700);
FORCEPROP 0 LAST $SEC 1
J 0
(1025 1750);
DISPLAY 0.680851 (1025 1750);
PAINT MONO (1025 1750);
DISPLAY INVISIBLE (1025 1750);
FORCEPROP 0 LAST CDS_SEC 1
J 0
(1025 1750);
DISPLAY 1.021277 (1025 1750);
DISPLAY INVISIBLE (1025 1750);
FORCEPROP 1 LASTPIN (975 1675) $PN 1
J 0
(980 1637);
DISPLAY 0.808511 (980 1637);
PAINT WHITE (980 1637);
DISPLAY INVISIBLE (980 1637);
FORCEPROP 1 LASTPIN (975 1475) $PN 2
J 0
(980 1485);
DISPLAY 0.808511 (980 1485);
PAINT WHITE (980 1485);
DISPLAY INVISIBLE (980 1485);
FORCEADD Q_RES..2
(975 2000);
FORCEPROP 1 LAST VALUE 15K
J 0
(1020 2075);
DISPLAY 0.510638 (1020 2075);
PAINT SKYBLUE (1020 2075);
FORCEPROP 1 LAST PACK_TYPE 0402LF
J 0
(1015 1825);
DISPLAY 0.510638 (1015 1825);
PAINT SKYBLUE (1015 1825);
FORCEPROP 1 LAST PART_NUMBER CS31502FB05
J 0
(1015 1875);
DISPLAY 0.510638 (1015 1875);
PAINT WHITE (1015 1875);
FORCEPROP 1 LAST MATERIAL CHIP
J 0
(1015 1925);
DISPLAY 0.510638 (1015 1925);
PAINT SKYBLUE (1015 1925);
FORCEPROP 1 LAST WATTAGE 1/16W
J 0
(1015 1975);
DISPLAY 0.510638 (1015 1975);
PAINT SKYBLUE (1015 1975);
FORCEPROP 1 LAST TOLERANCE 1%
J 0
(1020 2025);
DISPLAY 0.510638 (1020 2025);
PAINT SKYBLUE (1020 2025);
FORCEPROP 1 LAST PATH I98
J 0
(1025 2175);
DISPLAY 0.978723 (1025 2175);
PAINT WHITE (1025 2175);
DISPLAY INVISIBLE (1025 2175);
FORCEPROP 2 LAST CDS_LIB pure_quanta
J 0
(975 2000);
DISPLAY INVISIBLE (975 2000);
FORCEPROP 1 LAST LOCATION R831
J 0
(1020 2125);
DISPLAY 0.702128 (1020 2125);
PAINT YELLOW (1020 2125);
FORCEPROP 0 LAST $SEC 1
J 0
(1025 2175);
DISPLAY 0.680851 (1025 2175);
PAINT MONO (1025 2175);
DISPLAY INVISIBLE (1025 2175);
FORCEPROP 0 LAST CDS_SEC 1
J 0
(1025 2175);
DISPLAY 1.021277 (1025 2175);
DISPLAY INVISIBLE (1025 2175);
FORCEPROP 1 LASTPIN (975 2100) $PN 1
J 0
(980 2062);
DISPLAY 0.808511 (980 2062);
PAINT WHITE (980 2062);
DISPLAY INVISIBLE (980 2062);
FORCEPROP 1 LASTPIN (975 1900) $PN 2
J 0
(980 1910);
DISPLAY 0.808511 (980 1910);
PAINT WHITE (980 1910);
DISPLAY INVISIBLE (980 1910);
FORCEADD Q_RES..1
(-2025 1625);
FORCEPROP 1 LAST VALUE 0
J 2
(-1800 1625);
DISPLAY 0.510638 (-1800 1625);
PAINT SKYBLUE (-1800 1625);
FORCEPROP 1 LAST MATERIAL CHIP
J 0
(-1775 1625);
DISPLAY 0.510638 (-1775 1625);
PAINT SKYBLUE (-1775 1625);
FORCEPROP 1 LAST PACK_TYPE 0402LF
J 0
(-2100 1575);
DISPLAY 0.510638 (-2100 1575);
PAINT SKYBLUE (-2100 1575);
FORCEPROP 1 LAST PART_NUMBER CS00002JB13
J 0
(-2125 1675);
DISPLAY 0.510638 (-2125 1675);
PAINT WHITE (-2125 1675);
FORCEPROP 2 LAST CDS_LIB pure_quanta
J 0
(-2025 1625);
DISPLAY INVISIBLE (-2025 1625);
FORCEPROP 1 LAST PATH I99
J 0
(-2075 1775);
DISPLAY 0.978723 (-2075 1775);
PAINT WHITE (-2075 1775);
DISPLAY INVISIBLE (-2075 1775);
FORCEPROP 1 LAST WATTAGE 1/16W
J 2
(-2050 1475);
DISPLAY 0.510638 (-2050 1475);
PAINT SKYBLUE (-2050 1475);
DISPLAY INVISIBLE (-2050 1475);
FORCEPROP 1 LAST TOLERANCE 5%
J 0
(-2025 1525);
DISPLAY 0.510638 (-2025 1525);
PAINT SKYBLUE (-2025 1525);
DISPLAY INVISIBLE (-2025 1525);
FORCEPROP 1 LAST LOCATION R275
J 0
(-2275 1625);
DISPLAY 0.702128 (-2275 1625);
PAINT YELLOW (-2275 1625);
FORCEPROP 1 LASTPIN (-2125 1625) $PN 1
J 0
(-2113 1637);
DISPLAY 0.808511 (-2113 1637);
PAINT WHITE (-2113 1637);
FORCEPROP 1 LASTPIN (-1925 1625) $PN 2
J 0
(-1963 1637);
DISPLAY 0.808511 (-1963 1637);
PAINT WHITE (-1963 1637);
FORCEPROP 2 LAST $SEC 1
J 0
(-2150 1850);
DISPLAY 0.680851 (-2150 1850);
PAINT MONO (-2150 1850);
DISPLAY INVISIBLE (-2150 1850);
FORCEPROP 0 LAST CDS_SEC 1
J 0
(-2150 1850);
DISPLAY 0.680851 (-2150 1850);
PAINT MONO (-2150 1850);
DISPLAY INVISIBLE (-2150 1850);
FORCEADD QUANTA_TITLE_BLOCK_C..1
(5425 -2075);
FORCEPROP 0 LAST CDS_CON_LAST_MODIFIED Fri Aug 25 17:25:49 2023
J 0
(3540 -2060);
DISPLAY INVISIBLE (3540 -2060);
FORCEPROP 2 LAST Q_DEPT 
J 1
(1662 -2026);
DISPLAY 1.957447 (1662 -2026);
PAINT GREEN (1662 -2026);
FORCEPROP 1 LAST CUSTOM_TXT_CDS <CON_LAST_MODIFIED>
J 0
(3540 -2060);
DISPLAY 0.978723 (3540 -2060);
FORCEPROP 2 LAST CUSTOM_TXT_CDS <XR_PAGE_TITLE>
J 0
(-2465 3175);
DISPLAY 0.638298 (-2465 3175);
PAINT PINK (-2465 3175);
DISPLAY INVISIBLE (-2465 3175);
FORCEPROP 1 LAST CUSTOM_TXT_CDS <NAME_2>
J 0
(2250 -2025);
FORCEPROP 1 LAST CUSTOM_TXT_CDS <NAME_1>
J 0
(2250 -1900);
FORCEPROP 1 LAST CUSTOM_TXT_CDS <Q_NUMBER>
J 0
(4022 -1972);
DISPLAY 1.212766 (4022 -1972);
FORCEPROP 1 LAST CUSTOM_TXT_CDS <Q_PROJ>
J 0
(3043 -1973);
DISPLAY 1.212766 (3043 -1973);
FORCEPROP 1 LAST CUSTOM_TXT_CDS <Q_REV>
J 0
(5241 -1972);
DISPLAY 1.212766 (5241 -1972);
FORCEPROP 1 LAST CUSTOM_TXT_CDS <CON_PAGE_NUM> OF <CON_TOTAL_PAGES>
J 0
(4979 -2057);
DISPLAY 0.978723 (4979 -2057);
FORCEPROP 1 LAST Q_TITLE RT9059 - P1V8_AUX
J 0
(-3941 -2049);
DISPLAY 2.446809 (-3941 -2049);
PAINT GREEN (-3941 -2049);
FORCEPROP 1 LAST COMMENT_BODY TRUE
J 0
(5437 -2088);
DISPLAY 0.978723 (5437 -2088);
PAINT PEACH (5437 -2088);
DISPLAY INVISIBLE (5437 -2088);
FORCEPROP 2 LAST PAGE_BORDER TRUE
J 0
(-2465 3175);
DISPLAY 0.638298 (-2465 3175);
PAINT PINK (-2465 3175);
DISPLAY INVISIBLE (-2465 3175);
FORCEPROP 1 LAST CDS_LMAN_SYM_OUTLINE -9475,6775,100,-125
J 0
(5425 -2075);
DISPLAY 0.468085 (5425 -2075);
PAINT GREEN (5425 -2075);
DISPLAY INVISIBLE (5425 -2075);
FORCEPROP 2 LAST CDS_LIB pure_quanta
J 0
(5425 -2075);
DISPLAY INVISIBLE (5425 -2075);
FORCEPROP 2 LAST CDS_XR_PAGE_TITLE CR-54 : @SCM_LIB.SCM(SCH_1):PAGE54
J 0
(-2465 3175);
DISPLAY 0.638298 (-2465 3175);
PAINT PINK (-2465 3175);
DISPLAY INVISIBLE (-2465 3175);
FORCEADD DNS..2
(-2050 1800);
PAINT RED (-2050 1800);
FORCEPROP 1 LAST COMMENT_BODY TRUE
R 1
J 0
(-1975 1575);
DISPLAY 0.872340 (-1975 1575);
PAINT PEACH (-1975 1575);
DISPLAY INVISIBLE (-1975 1575);
FORCEPROP 2 LAST CDS_LIB mstr_misc
J 0
(-2050 1800);
DISPLAY INVISIBLE (-2050 1800);
FORCEADD DNS..2
(-1650 2450);
PAINT RED (-1650 2450);
FORCEPROP 2 LAST CDS_LIB mstr_misc
J 0
(-1650 2450);
DISPLAY INVISIBLE (-1650 2450);
FORCEPROP 1 LAST COMMENT_BODY TRUE
R 1
J 0
(-1575 2225);
DISPLAY 0.872340 (-1575 2225);
PAINT PEACH (-1575 2225);
DISPLAY INVISIBLE (-1575 2225);
FORCEADD DNS..2
(-1100 1425);
PAINT RED (-1100 1425);
FORCEPROP 1 LAST COMMENT_BODY TRUE
R 1
J 0
(-1025 1200);
DISPLAY 0.872340 (-1025 1200);
PAINT PEACH (-1025 1200);
DISPLAY INVISIBLE (-1025 1200);
FORCEPROP 2 LAST CDS_LIB mstr_misc
J 0
(-1100 1425);
DISPLAY INVISIBLE (-1100 1425);
FORCEADD CAD_NOTE..1
(-2600 1000);
FORCEPROP 0 LAST L1 THE CAP & DAMPING RS FOR PWRGD SHOULD CLOSE TO DRIVE-END
J 0
(-2650 800);
DISPLAY 1.021277 (-2650 800);
PAINT WHITE (-2650 800);
FORCEPROP 1 LAST COMMENT_BODY TRUE
J 0
(-2575 1100);
DISPLAY 0.978723 (-2575 1100);
PAINT PEACH (-2575 1100);
DISPLAY INVISIBLE (-2575 1100);
FORCEPROP 2 LAST CDS_LIB logical_power
J 0
(-2600 1000);
DISPLAY INVISIBLE (-2600 1000);
WIRE 16 -1 (-725 1950)(-725 1975);
WIRE 16 -1 (1500 175)(1500 250);
WIRE 16 -1 (1500 175)(1625 175);
WIRE 16 -1 (1500 150)(1500 175);
WIRE 16 -1 (3000 2225)(3000 2350);
WIRE 16 -1 (3000 2225)(2500 2225);
WIRE 16 -1 (1050 3400)(1050 3175);
WIRE 16 -1 (-1000 3100)(-1000 3225);
WIRE 16 -1 (-550 3100)(-1000 3100);
WIRE 16 -1 (-1000 2950)(-1000 3100);
WIRE 16 -1 (-375 -925)(-375 -1000);
WIRE 16 -1 (350 -775)(350 -900);
WIRE 16 -1 (350 -775)(425 -775);
WIRE 16 -1 (1500 -50)(1500 -125);
WIRE 16 -1 (-1075 1325)(-1075 1275);
WIRE 16 -1 (550 1450)(550 1400);
WIRE 16 -1 (550 1450)(975 1450);
WIRE 16 -1 (550 1625)(550 1450);
WIRE 16 -1 (-1000 2575)(-1000 2750);
WIRE 16 -1 (1850 1625)(1850 1725);
WIRE 16 -1 (1050 2750)(1050 2925);
WIRE 16 -1 (400 1625)(550 1625);
WIRE 16 -1 (975 1475)(975 1450);
WIRE 16 -1 (400 2125)(625 2125);
WIRE 16 -1 (625 2125)(625 2175);
WIRE 16 -1 (400 2175)(625 2175);
WIRE 16 -1 (625 2175)(625 2225);
WIRE 16 -1 (400 2225)(625 2225);
WIRE 16 -1 (625 2225)(975 2225);
WIRE 16 -1 (975 2100)(975 2225);
WIRE 16 -1 (975 2225)(1850 2225);
WIRE 16 -1 (1850 2100)(1850 2225);
WIRE 16 -1 (2500 2225)(1850 2225);
WIRE 16 -1 (2500 2225)(2500 2100);
WIRE 16 -1 (1050 3175)(1050 3125);
WIRE 16 -1 (625 3175)(1050 3175);
WIRE 16 -1 (625 2625)(625 3175);
WIRE 16 -1 (400 2625)(625 2625);
WIRE 16 -1 (625 2575)(625 2625);
WIRE 16 -1 (400 2575)(625 2575);
WIRE 16 -1 (625 2525)(625 2575);
WIRE 16 -1 (400 2525)(625 2525);
WIRE 16 -1 (-400 2625)(-550 2625);
WIRE 16 -1 (-550 2625)(-550 3100);
WIRE 16 -1 (-1525 2450)(-1325 2450);
WIRE 16 -1 (-1325 2450)(-1325 2175);
WIRE 16 -1 (-1325 2175)(-400 2175);
FORCEPROP 2 LAST SIG_NAME EN_P1V8_R
J 0
(-1185 2185);
DISPLAY 0.808511 (-1185 2185);
WIRE 16 -1 (-1525 2175)(-1325 2175);
WIRE 16 -1 (-2700 2175)(-1725 2175);
FORCEPROP 0 LAST SIG_NAME EN_P1V8
J 0
(-2635 2185);
DISPLAY 0.808511 (-2635 2185);
WIRE 16 -1 (-2700 2450)(-1725 2450);
FORCEPROP 0 LAST SIG_NAME PWRGD_P2V5_AUX_R3
J 0
(-2635 2460);
DISPLAY 0.808511 (-2635 2460);
WIRE 16 -1 (-1925 1800)(-1675 1800);
WIRE 16 -1 (-1675 1800)(-1675 1625);
WIRE 16 -1 (-1925 1625)(-1675 1625);
WIRE 16 -1 (-1675 1625)(-1075 1625);
FORCEPROP 2 LAST SIG_NAME PWRGD_P1V8_AUX_R
J 0
(-1610 1635);
DISPLAY 0.808511 (-1610 1635);
WIRE 16 -1 (-1075 1625)(-1075 1525);
WIRE 16 -1 (-1075 1625)(-725 1625);
WIRE 16 -1 (-400 1625)(-725 1625);
WIRE 16 -1 (-725 1750)(-725 1625);
WIRE 16 -1 (1525 -425)(1625 -425);
WIRE 16 -1 (1625 -425)(1625 175);
WIRE 16 -1 (-525 -625)(-375 -625);
WIRE 16 -1 (-375 -625)(425 -625);
FORCEPROP 2 LAST SIG_NAME PWRGD_P3V3_RGM_R2
J 0
(-335 -615);
DISPLAY 0.851064 (-335 -615);
WIRE 16 -1 (-375 -725)(-375 -625);
WIRE 16 -1 (-1450 -625)(-725 -625);
FORCEPROP 0 LAST SIG_NAME PWRGD_P3V3_RGM
J 0
(-1460 -615);
DISPLAY 0.808511 (-1460 -615);
WIRE 16 2175 (-1500 300)(-1500 -75);
WIRE 16 2175 (-2625 -75)(-1500 -75);
WIRE 16 2175 (-2625 300)(-1500 300);
WIRE 16 2175 (-2625 300)(-2625 -75);
WIRE 16 -1 (-2125 1800)(-3025 1800);
FORCEPROP 2 LAST SIG_NAME PWRGD_P1V8_AUX_R3
J 0
(-3010 1810);
DISPLAY 0.808511 (-3010 1810);
WIRE 16 -1 (-2125 1625)(-3025 1625);
FORCEPROP 2 LAST SIG_NAME PWRGD_P1V8_AUX
J 0
(-3010 1635);
DISPLAY 0.808511 (-3010 1635);
WIRE 16 -1 (2925 -775)(1525 -775);
FORCEPROP 2 LAST SIG_NAME EN_P1V8
J 2
(2840 -765);
DISPLAY 0.808511 (2840 -765);
WIRE 16 -1 (-725 -200)(425 -200);
FORCEPROP 0 LAST SIG_NAME PWRGD_P5V_AUX
J 0
(-610 -190);
DISPLAY 0.808511 (-610 -190);
WIRE 16 -1 (425 -200)(425 -425);
WIRE 74 2175 (3150 4175)(4949 4175);
WIRE 74 2175 (4949 4175)(4949 3600);
WIRE 74 2175 (3150 4175)(3150 3600);
WIRE 74 2175 (3150 3600)(4949 3600);
WIRE 16 -1 (2500 1900)(2500 1725);
WIRE 16 -1 (1850 1725)(1850 1900);
WIRE 16 -1 (2500 1725)(1850 1725);
WIRE 16 -1 (975 1825)(400 1825);
FORCEPROP 2 LAST SIG_NAME U41_ADJ
J 0
(615 1835);
DISPLAY 0.808511 (615 1835);
WIRE 16 -1 (975 1825)(975 1675);
WIRE 16 -1 (975 1825)(975 1900);
DOT 1 (-1325 2175);
DOT 1 (-375 -625);
DOT 1 (1500 175);
DOT 1 (975 2225);
DOT 1 (1850 2225);
DOT 1 (2500 2225);
DOT 1 (625 2575);
DOT 1 (625 2625);
DOT 1 (550 1450);
DOT 1 (975 1825);
DOT 1 (625 2225);
DOT 1 (-1000 3100);
DOT 1 (1850 1725);
DOT 1 (1050 3175);
DOT 1 (-725 1625);
DOT 1 (625 2175);
DOT 1 (-1075 1625);
DOT 1 (-1675 1625);
FORCENOTE
VNOM=0.8(1+RA/RB)=1.8
(725 1125) 0;
DISPLAY LEFT (725 1125);
DISPLAY 1.021277 (725 1125);
PAINT WHITE (725 1125);
FORCENOTE
IC TABLE
(-2525 200) 0;
DISPLAY LEFT (-2525 200);
DISPLAY 1.170213 (-2525 200);
FORCENOTE
1ST AL009059000
(-2525 100) 0;
DISPLAY LEFT (-2525 100);
DISPLAY 1.170213 (-2525 100);
FORCENOTE
2ND AL009661002
(-2525 0) 0;
DISPLAY LEFT (-2525 0);
DISPLAY 1.170213 (-2525 0);
FORCENOTE
PWRGD_FALL DELAY 230US
(-1050 -1225) 0;
DISPLAY LEFT (-1050 -1225);
DISPLAY 1.170213 (-1050 -1225);
FORCENOTE
P1V8_AUX
(-325 3925) 0;
DISPLAY LEFT (-325 3925);
DISPLAY 3.148936 (-325 3925);
FORCENOTE
PD=(3.3-1.8)V*0.33A=0.495W
(3200 3675) 0;
DISPLAY LEFT (3200 3675);
DISPLAY 0.936170 (3200 3675);
PAINT WHITE (3200 3675);
FORCENOTE
OUTPUT VOLTAGE=1.8V
(3200 3975) 0;
DISPLAY LEFT (3200 3975);
DISPLAY 1.042553 (3200 3975);
PAINT WHITE (3200 3975);
FORCENOTE
AC<+/-2%
(3200 3750) 0;
DISPLAY LEFT (3200 3750);
DISPLAY 0.936170 (3200 3750);
PAINT WHITE (3200 3750);
FORCENOTE
OUTPUT RIPPLE<+/-1%
(3200 3900) 0;
DISPLAY LEFT (3200 3900);
DISPLAY 0.936170 (3200 3900);
PAINT WHITE (3200 3900);
FORCENOTE
DESIGN SPECIFICATION
(3200 4075) 0;
DISPLAY LEFT (3200 4075);
DISPLAY 1.170213 (3200 4075);
PAINT WHITE (3200 4075);
FORCENOTE
DC<+/-3%
(3200 3825) 0;
DISPLAY LEFT (3200 3825);
DISPLAY 0.936170 (3200 3825);
PAINT WHITE (3200 3825);
QUIT
